(kicad_pcb
	(version 20260206)
	(generator "pcbnew")
	(generator_version "10.0")
	(general
		(thickness 1.6)
		(legacy_teardrops no)
	)
	(paper "A4")
	(title_block
		(title "04192023_DAF0TMB3IC0_F0TG_MB_C_brd_V02_OCP.brd")
		(comment 1 "Grand Teton / footprints 3425-3431 of 8354")
	)
	(layers
		(0 "F.Cu" signal "TOP")
		(4 "In1.Cu" signal "GND")
		(6 "In2.Cu" signal "IN1")
		(8 "In3.Cu" signal "GND1")
		(10 "In4.Cu" signal "IN2")
		(12 "In5.Cu" signal "GND2")
		(14 "In6.Cu" signal "IN3")
		(16 "In7.Cu" signal "GND3")
		(18 "In8.Cu" signal "VCC")
		(20 "In9.Cu" signal "VCC1")
		(22 "In10.Cu" signal "GND4")
		(24 "In11.Cu" signal "IN4")
		(26 "In12.Cu" signal "GND5")
		(28 "In13.Cu" signal "IN5")
		(30 "In14.Cu" signal "GND6")
		(32 "In15.Cu" signal "IN6")
		(34 "In16.Cu" signal "GND7")
		(2 "B.Cu" signal "BOTTOM")
		(9 "F.Adhes" user "F.Adhesive")
		(11 "B.Adhes" user "B.Adhesive")
		(13 "F.Paste" user "Package Geometry/Pastemask Top")
		(15 "B.Paste" user "Package Geometry/Pastemask Bottom")
		(5 "F.SilkS" user "Ref Des/Silkscreen Top")
		(7 "B.SilkS" user "Ref Des/Silkscreen Bottom")
		(1 "F.Mask" user "Board Geometry/Soldermask Top")
		(3 "B.Mask" user "Board Geometry/Soldermask Bottom")
		(17 "Dwgs.User" user "User.Drawings")
		(19 "Cmts.User" user "User.Comments")
		(21 "Eco1.User" user "User.Eco1")
		(23 "Eco2.User" user "User.Eco2")
		(25 "Edge.Cuts" user "Board Geometry/Outline")
		(27 "Margin" user)
		(31 "F.CrtYd" user "Package Geometry/Place Bound Top")
		(29 "B.CrtYd" user "Package Geometry/Place Bound Bottom")
		(35 "F.Fab" user "Ref Des/Assembly Top")
		(33 "B.Fab" user "Ref Des/Assembly Bottom")
	)
	(footprint ""
		(layer "F.Cu")
		(at 501.233948 7.574534 -90)
		(property "Reference" "X8009"
			(at -1.815338 4.793488 0)
			(unlocked yes)
			(layer "F.SilkS")
			(effects
				(font
					(size 0.7874 0.5842)
					(thickness 0.1524)
				)
				(justify left)
			)
		)
		(property "Value" ""
			(at 0 0 270)
			(layer "F.Fab")
			(effects
				(font
					(size 1.27 1.27)
				)
			)
		)
		(property "Device Type" "TP_TDR_4P_FTS_TH-TP_TDR_4P_DIP,EMPTY,TP15"
			(at 1.30175 1.27 0)
			(unlocked yes)
			(layer "F.Fab")
			(hide yes)
			(effects
				(font
					(size 0.635 0.4064)
					(thickness 0.1524)
				)
			)
		)
		(property "User Part Number" "N_A"
			(at 1.30175 1.27 0)
			(unlocked yes)
			(layer "Cmts.User")
			(hide yes)
			(effects
				(font
					(size 0.635 0.4064)
					(thickness 0.1524)
				)
			)
		)
		(duplicate_pad_numbers_are_jumpers no)
		(fp_line
			(start 0 3.81)
			(end 2.54 3.81)
			(stroke
				(width 0.1524)
				(type default)
			)
			(layer "F.SilkS")
		)
		(fp_line
			(start 2.54 3.81)
			(end 2.54 3.6703)
			(stroke
				(width 0.1524)
				(type default)
			)
			(layer "F.SilkS")
		)
		(fp_line
			(start 0 3.175)
			(end 0 3.81)
			(stroke
				(width 0.1524)
				(type default)
			)
			(layer "F.SilkS")
		)
		(fp_line
			(start 2.54 1.4097)
			(end 2.54 1.1303)
			(stroke
				(width 0.1524)
				(type default)
			)
			(layer "F.SilkS")
		)
		(fp_line
			(start 0 0.635)
			(end 0 1.905)
			(stroke
				(width 0.1524)
				(type default)
			)
			(layer "F.SilkS")
		)
		(fp_line
			(start 2.54 -1.1303)
			(end 2.54 -1.27)
			(stroke
				(width 0.1524)
				(type default)
			)
			(layer "F.SilkS")
		)
		(fp_line
			(start 0 -1.27)
			(end 0 -0.635)
			(stroke
				(width 0.1524)
				(type default)
			)
			(layer "F.SilkS")
		)
		(fp_line
			(start 2.54 -1.27)
			(end 0 -1.27)
			(stroke
				(width 0.1524)
				(type default)
			)
			(layer "F.SilkS")
		)
		(fp_poly
			(pts
				(xy -2.285746 -0.762) (xy -0.761746 0) (xy -2.285746 0.762)
			)
			(stroke
				(width 0)
				(type default)
			)
			(fill yes)
			(layer "F.SilkS")
		)
		(fp_line
			(start 0 3.81)
			(end 2.54 3.81)
			(stroke
				(width 0.1)
				(type default)
			)
			(layer "F.Fab")
		)
		(fp_line
			(start 2.54 3.81)
			(end 2.54 -1.27)
			(stroke
				(width 0.1)
				(type default)
			)
			(layer "F.Fab")
		)
		(fp_line
			(start 0 -1.27)
			(end 0 3.81)
			(stroke
				(width 0.1)
				(type default)
			)
			(layer "F.Fab")
		)
		(fp_line
			(start 2.54 -1.27)
			(end 0 -1.27)
			(stroke
				(width 0.1)
				(type default)
			)
			(layer "F.Fab")
		)
		(fp_poly
			(pts
				(xy -0.761746 0) (xy -2.285746 -0.762) (xy -2.285746 0.762)
			)
			(stroke
				(width 0)
				(type default)
			)
			(fill yes)
			(layer "F.Fab")
		)
		(pad "1" thru_hole circle
			(at 0 0 270)
			(size 1.0033 1.0033)
			(drill 0.249936)
			(layers "*.Cu" "*.Mask")
			(remove_unused_layers no)
			(net "TDR_DIFF_85_IN2_DN")
			(clearance 0.10795)
			(thermal_gap 0.10795)
			(padstack
				(mode front_inner_back)
				(layer "Inner"
					(shape circle)
					(size 0.8001 0.8001)
					(clearance 0.1524)
				)
				(layer "B.Cu"
					(shape circle)
					(size 1.0033 1.0033)
					(clearance 0.10795)
				)
			)
		)
		(pad "2" thru_hole circle
			(at 2.54 0 270)
			(size 1.9939 1.9939)
			(drill 0.249936)
			(layers "*.Cu" "*.Mask")
			(remove_unused_layers no)
			(net "T1_GND")
			(clearance 0.10795)
			(thermal_gap 0.10795)
			(padstack
				(mode front_inner_back)
				(layer "Inner"
					(shape circle)
					(size 0.8001 0.8001)
					(clearance 0.1524)
				)
				(layer "B.Cu"
					(shape circle)
					(size 1.9939 1.9939)
					(clearance 0.10795)
				)
			)
		)
		(pad "3" thru_hole circle
			(at 2.54 2.54 270)
			(size 1.9939 1.9939)
			(drill 0.249936)
			(layers "*.Cu" "*.Mask")
			(remove_unused_layers no)
			(net "T1_GND")
			(clearance 0.10795)
			(thermal_gap 0.10795)
			(padstack
				(mode front_inner_back)
				(layer "Inner"
					(shape circle)
					(size 0.8001 0.8001)
					(clearance 0.1524)
				)
				(layer "B.Cu"
					(shape circle)
					(size 1.9939 1.9939)
					(clearance 0.10795)
				)
			)
		)
		(pad "4" thru_hole circle
			(at 0 2.54 270)
			(size 1.0033 1.0033)
			(drill 0.249936)
			(layers "*.Cu" "*.Mask")
			(remove_unused_layers no)
			(net "TDR_DIFF_85_IN2_DP")
			(clearance 0.10795)
			(thermal_gap 0.10795)
			(padstack
				(mode front_inner_back)
				(layer "Inner"
					(shape circle)
					(size 0.8001 0.8001)
					(clearance 0.1524)
				)
				(layer "B.Cu"
					(shape circle)
					(size 1.0033 1.0033)
					(clearance 0.10795)
				)
			)
		)
	)
	(footprint ""
		(layer "F.Cu")
		(at 403.682962 -57.2135 180)
		(property "Reference" "R1620"
			(at 0 0 180)
			(layer "F.SilkS")
			(hide yes)
			(effects
				(font
					(size 1.27 1.27)
				)
			)
		)
		(property "Value" ""
			(at 0 0 180)
			(layer "F.Fab")
			(effects
				(font
					(size 1.27 1.27)
				)
			)
		)
		(duplicate_pad_numbers_are_jumpers no)
		(fp_line
			(start 0.7874 0.4064)
			(end -0.7874 0.4064)
			(stroke
				(width 0.1524)
				(type default)
			)
			(layer "F.SilkS")
		)
		(fp_line
			(start 0.7874 -0.4064)
			(end 0.7874 0.4064)
			(stroke
				(width 0.1524)
				(type default)
			)
			(layer "F.SilkS")
		)
		(fp_line
			(start -0.7874 0.4064)
			(end -0.7874 -0.4064)
			(stroke
				(width 0.1524)
				(type default)
			)
			(layer "F.SilkS")
		)
		(fp_line
			(start -0.7874 -0.4064)
			(end 0.7874 -0.4064)
			(stroke
				(width 0.1524)
				(type default)
			)
			(layer "F.SilkS")
		)
		(fp_line
			(start 0.67945 0.3048)
			(end 0.120396 0.3048)
			(stroke
				(width 0.1)
				(type default)
			)
			(layer "F.Fab")
		)
		(fp_line
			(start 0.67945 -0.3048)
			(end 0.67945 0.3048)
			(stroke
				(width 0.1)
				(type default)
			)
			(layer "F.Fab")
		)
		(fp_line
			(start 0.12065 -0.2794)
			(end 0.12065 -0.3048)
			(stroke
				(width 0.1)
				(type default)
			)
			(layer "F.Fab")
		)
		(fp_line
			(start 0.12065 -0.3048)
			(end 0.67945 -0.3048)
			(stroke
				(width 0.1)
				(type default)
			)
			(layer "F.Fab")
		)
		(fp_line
			(start 0.120396 0.3048)
			(end 0.120396 0.2794)
			(stroke
				(width 0.1)
				(type default)
			)
			(layer "F.Fab")
		)
		(fp_line
			(start 0.120396 0.2794)
			(end -0.12065 0.2794)
			(stroke
				(width 0.1)
				(type default)
			)
			(layer "F.Fab")
		)
		(fp_line
			(start -0.12065 0.3048)
			(end -0.67945 0.3048)
			(stroke
				(width 0.1)
				(type default)
			)
			(layer "F.Fab")
		)
		(fp_line
			(start -0.12065 0.2794)
			(end -0.12065 0.3048)
			(stroke
				(width 0.1)
				(type default)
			)
			(layer "F.Fab")
		)
		(fp_line
			(start -0.12065 -0.2794)
			(end 0.12065 -0.2794)
			(stroke
				(width 0.1)
				(type default)
			)
			(layer "F.Fab")
		)
		(fp_line
			(start -0.12065 -0.305054)
			(end -0.12065 -0.2794)
			(stroke
				(width 0.1)
				(type default)
			)
			(layer "F.Fab")
		)
		(fp_line
			(start -0.67945 0.3048)
			(end -0.67945 -0.305054)
			(stroke
				(width 0.1)
				(type default)
			)
			(layer "F.Fab")
		)
		(fp_line
			(start -0.67945 -0.305054)
			(end -0.12065 -0.305054)
			(stroke
				(width 0.1)
				(type default)
			)
			(layer "F.Fab")
		)
		(pad "1" smd circle
			(at -0.40005 0 180)
			(size 0 0)
			(layers "F.Cu" "F.Mask" "F.Paste")
			(net "HDT_HDR_TRST_N")
		)
		(pad "2" smd circle
			(at 0.40005 0 180)
			(size 0 0)
			(layers "F.Cu" "F.Mask" "F.Paste")
			(net "HDT_HDR_TRST_N_R")
		)
	)
	(footprint ""
		(layer "F.Cu")
		(at 110.365794 -383.7432)
		(property "Reference" "R923"
			(at 0 0 0)
			(layer "F.SilkS")
			(hide yes)
			(effects
				(font
					(size 1.27 1.27)
				)
			)
		)
		(property "Value" ""
			(at 0 0 0)
			(layer "F.Fab")
			(effects
				(font
					(size 1.27 1.27)
				)
			)
		)
		(duplicate_pad_numbers_are_jumpers no)
		(fp_line
			(start -0.32512 -0.175006)
			(end 0.32512 -0.175006)
			(stroke
				(width 0.1)
				(type default)
			)
			(layer "F.Fab")
		)
		(fp_line
			(start -0.32512 0.175006)
			(end -0.32512 -0.175006)
			(stroke
				(width 0.1)
				(type default)
			)
			(layer "F.Fab")
		)
		(fp_line
			(start 0.32512 -0.175006)
			(end 0.32512 0.175006)
			(stroke
				(width 0.1)
				(type default)
			)
			(layer "F.Fab")
		)
		(fp_line
			(start 0.32512 0.175006)
			(end -0.32512 0.175006)
			(stroke
				(width 0.1)
				(type default)
			)
			(layer "F.Fab")
		)
		(pad "1" smd rect
			(at -0.2667 0)
			(size 0.3048 0.381)
			(layers "F.Cu" "F.Mask" "F.Paste")
			(net "TEST2_RT_CPU1_P3")
		)
		(pad "2" smd rect
			(at 0.2667 0 180)
			(size 0.3048 0.381)
			(layers "F.Cu" "F.Mask" "F.Paste")
			(net "GND")
		)
	)
	(footprint ""
		(layer "F.Cu")
		(at 13.21816 -381.202438 90)
		(property "Reference" "PC6623"
			(at 0 0 90)
			(layer "F.SilkS")
			(hide yes)
			(effects
				(font
					(size 1.27 1.27)
				)
			)
		)
		(property "Value" ""
			(at 0 0 90)
			(layer "F.Fab")
			(effects
				(font
					(size 1.27 1.27)
				)
			)
		)
		(duplicate_pad_numbers_are_jumpers no)
		(fp_line
			(start 0.7874 -0.4064)
			(end 0.7874 0.4064)
			(stroke
				(width 0.1524)
				(type default)
			)
			(layer "F.SilkS")
		)
		(fp_line
			(start -0.7874 -0.4064)
			(end 0.7874 -0.4064)
			(stroke
				(width 0.1524)
				(type default)
			)
			(layer "F.SilkS")
		)
		(fp_line
			(start 0.7874 0.4064)
			(end -0.7874 0.4064)
			(stroke
				(width 0.1524)
				(type default)
			)
			(layer "F.SilkS")
		)
		(fp_line
			(start -0.7874 0.4064)
			(end -0.7874 -0.4064)
			(stroke
				(width 0.1524)
				(type default)
			)
			(layer "F.SilkS")
		)
		(fp_line
			(start -0.12065 -0.305054)
			(end -0.12065 -0.2794)
			(stroke
				(width 0.1)
				(type default)
			)
			(layer "F.Fab")
		)
		(fp_line
			(start -0.67945 -0.305054)
			(end -0.12065 -0.305054)
			(stroke
				(width 0.1)
				(type default)
			)
			(layer "F.Fab")
		)
		(fp_line
			(start 0.67945 -0.3048)
			(end 0.67945 0.3048)
			(stroke
				(width 0.1)
				(type default)
			)
			(layer "F.Fab")
		)
		(fp_line
			(start 0.12065 -0.3048)
			(end 0.67945 -0.3048)
			(stroke
				(width 0.1)
				(type default)
			)
			(layer "F.Fab")
		)
		(fp_line
			(start 0.12065 -0.2794)
			(end 0.12065 -0.3048)
			(stroke
				(width 0.1)
				(type default)
			)
			(layer "F.Fab")
		)
		(fp_line
			(start -0.12065 -0.2794)
			(end 0.12065 -0.2794)
			(stroke
				(width 0.1)
				(type default)
			)
			(layer "F.Fab")
		)
		(fp_line
			(start 0.120396 0.2794)
			(end -0.12065 0.2794)
			(stroke
				(width 0.1)
				(type default)
			)
			(layer "F.Fab")
		)
		(fp_line
			(start -0.12065 0.2794)
			(end -0.12065 0.3048)
			(stroke
				(width 0.1)
				(type default)
			)
			(layer "F.Fab")
		)
		(fp_line
			(start 0.67945 0.3048)
			(end 0.120396 0.3048)
			(stroke
				(width 0.1)
				(type default)
			)
			(layer "F.Fab")
		)
		(fp_line
			(start 0.120396 0.3048)
			(end 0.120396 0.2794)
			(stroke
				(width 0.1)
				(type default)
			)
			(layer "F.Fab")
		)
		(fp_line
			(start -0.12065 0.3048)
			(end -0.67945 0.3048)
			(stroke
				(width 0.1)
				(type default)
			)
			(layer "F.Fab")
		)
		(fp_line
			(start -0.67945 0.3048)
			(end -0.67945 -0.305054)
			(stroke
				(width 0.1)
				(type default)
			)
			(layer "F.Fab")
		)
		(pad "1" smd circle
			(at -0.40005 0 90)
			(size 0 0)
			(layers "F.Cu" "F.Mask" "F.Paste")
			(net "P0V9_CPU1_RT_2D")
		)
		(pad "2" smd circle
			(at 0.40005 0 90)
			(size 0 0)
			(layers "F.Cu" "F.Mask" "F.Paste")
			(net "GND")
		)
	)
	(footprint ""
		(layer "F.Cu")
		(at 432.01336 -361.827826 180)
		(property "Reference" "PC220"
			(at 1.87452 -2.965704 0)
			(unlocked yes)
			(layer "F.SilkS")
			(effects
				(font
					(size 0.7874 0.5842)
					(thickness 0.1524)
				)
				(justify left)
			)
		)
		(property "Value" ""
			(at 0 0 180)
			(layer "F.Fab")
			(effects
				(font
					(size 1.27 1.27)
				)
			)
		)
		(duplicate_pad_numbers_are_jumpers no)
		(fp_line
			(start -3.400044 1.249934)
			(end 3.400044 1.249934)
			(stroke
				(width 0.1524)
				(type default)
			)
			(layer "F.SilkS")
		)
		(fp_circle
			(center 0 1.249934)
			(end -3.400044 1.249934)
			(stroke
				(width 0.1524)
				(type default)
			)
			(fill no)
			(layer "F.SilkS")
		)
		(fp_poly
			(pts
				(arc
					(start 3.400044 1.249934)
					(mid 0 4.649978)
					(end -3.400044 1.249934)
				)
			)
			(stroke
				(width 0)
				(type default)
			)
			(fill yes)
			(layer "F.SilkS")
		)
		(fp_circle
			(center 0 1.249934)
			(end -3.400044 1.249934)
			(stroke
				(width 0.1)
				(type default)
			)
			(fill no)
			(layer "F.Fab")
		)
		(pad "1" thru_hole rect
			(at 0 0 180)
			(size 1.524 1.524)
			(drill 1.016)
			(layers "*.Cu" "*.Mask")
			(remove_unused_layers no)
			(net "SW_P12V_AUX_PVDD11_S3_P0_FLT")
			(clearance 0)
			(padstack
				(mode front_inner_back)
				(layer "Inner"
					(shape circle)
					(size 1.524 1.524)
					(clearance 0)
				)
				(layer "B.Cu"
					(shape rect)
					(size 1.524 1.524)
					(clearance 0)
				)
			)
		)
		(pad "2" thru_hole circle
			(at 0 2.500122 180)
			(size 1.524 1.524)
			(drill 1.016)
			(layers "*.Cu" "*.Mask")
			(remove_unused_layers no)
			(net "GND")
			(clearance 0)
		)
	)
	(footprint ""
		(layer "F.Cu")
		(at 449.955666 -380.13767 -90)
		(property "Reference" "PC6574"
			(at 4.75234 2.153666 0)
			(unlocked yes)
			(layer "F.SilkS")
			(effects
				(font
					(size 0.7874 0.5842)
					(thickness 0.1524)
				)
				(justify left)
			)
		)
		(property "Value" ""
			(at 0 0 270)
			(layer "F.Fab")
			(effects
				(font
					(size 1.27 1.27)
				)
			)
		)
		(duplicate_pad_numbers_are_jumpers no)
		(fp_line
			(start -1.988058 2.750058)
			(end 2.750058 2.750058)
			(stroke
				(width 0.1524)
				(type default)
			)
			(layer "F.SilkS")
		)
		(fp_line
			(start 2.750058 2.750058)
			(end 2.750058 0.9398)
			(stroke
				(width 0.1524)
				(type default)
			)
			(layer "F.SilkS")
		)
		(fp_line
			(start -2.750058 1.988058)
			(end -1.988058 2.750058)
			(stroke
				(width 0.1524)
				(type default)
			)
			(layer "F.SilkS")
		)
		(fp_line
			(start -2.750058 0.9398)
			(end -2.750058 1.988058)
			(stroke
				(width 0.1524)
				(type default)
			)
			(layer "F.SilkS")
		)
		(fp_line
			(start 2.750058 -0.9398)
			(end 2.750058 -2.750058)
			(stroke
				(width 0.1524)
				(type default)
			)
			(layer "F.SilkS")
		)
		(fp_line
			(start -2.750058 -1.988058)
			(end -2.750058 -0.9398)
			(stroke
				(width 0.1524)
				(type default)
			)
			(layer "F.SilkS")
		)
		(fp_line
			(start -1.988058 -2.750058)
			(end -2.750058 -1.988058)
			(stroke
				(width 0.1524)
				(type default)
			)
			(layer "F.SilkS")
		)
		(fp_line
			(start 2.750058 -2.750058)
			(end -1.988058 -2.750058)
			(stroke
				(width 0.1524)
				(type default)
			)
			(layer "F.SilkS")
		)
		(fp_line
			(start -2.750058 2.750058)
			(end 2.750058 2.750058)
			(stroke
				(width 0.1)
				(type default)
			)
			(layer "F.Fab")
		)
		(fp_line
			(start 2.750058 2.750058)
			(end 2.750058 -2.750058)
			(stroke
				(width 0.1)
				(type default)
			)
			(layer "F.Fab")
		)
		(fp_line
			(start -2.750058 -2.750058)
			(end -2.750058 2.750058)
			(stroke
				(width 0.1)
				(type default)
			)
			(layer "F.Fab")
		)
		(fp_line
			(start 2.750058 -2.750058)
			(end -2.750058 -2.750058)
			(stroke
				(width 0.1)
				(type default)
			)
			(layer "F.Fab")
		)
		(pad "1" smd rect
			(at -2.199894 0)
			(size 1.6002 3.0226)
			(layers "F.Cu" "F.Mask" "F.Paste")
			(net "P0V9_CPU0_RT_2D")
		)
		(pad "2" smd rect
			(at 2.199894 0)
			(size 1.6002 3.0226)
			(layers "F.Cu" "F.Mask" "F.Paste")
			(net "GND")
		)
	)
	(footprint ""
		(layer "F.Cu")
		(at 239.374426 -294.978074 90)
		(property "Reference" "PC6507"
			(at 0 0 90)
			(layer "F.SilkS")
			(hide yes)
			(effects
				(font
					(size 1.27 1.27)
				)
			)
		)
		(property "Value" ""
			(at 0 0 90)
			(layer "F.Fab")
			(effects
				(font
					(size 1.27 1.27)
				)
			)
		)
		(duplicate_pad_numbers_are_jumpers no)
		(fp_line
			(start 0.7874 -0.4064)
			(end 0.7874 0.4064)
			(stroke
				(width 0.1524)
				(type default)
			)
			(layer "F.SilkS")
		)
		(fp_line
			(start -0.7874 -0.4064)
			(end 0.7874 -0.4064)
			(stroke
				(width 0.1524)
				(type default)
			)
			(layer "F.SilkS")
		)
		(fp_line
			(start 0.7874 0.4064)
			(end -0.7874 0.4064)
			(stroke
				(width 0.1524)
				(type default)
			)
			(layer "F.SilkS")
		)
		(fp_line
			(start -0.7874 0.4064)
			(end -0.7874 -0.4064)
			(stroke
				(width 0.1524)
				(type default)
			)
			(layer "F.SilkS")
		)
		(fp_line
			(start -0.12065 -0.305054)
			(end -0.12065 -0.2794)
			(stroke
				(width 0.1)
				(type default)
			)
			(layer "F.Fab")
		)
		(fp_line
			(start -0.67945 -0.305054)
			(end -0.12065 -0.305054)
			(stroke
				(width 0.1)
				(type default)
			)
			(layer "F.Fab")
		)
		(fp_line
			(start 0.67945 -0.3048)
			(end 0.67945 0.3048)
			(stroke
				(width 0.1)
				(type default)
			)
			(layer "F.Fab")
		)
		(fp_line
			(start 0.12065 -0.3048)
			(end 0.67945 -0.3048)
			(stroke
				(width 0.1)
				(type default)
			)
			(layer "F.Fab")
		)
		(fp_line
			(start 0.12065 -0.2794)
			(end 0.12065 -0.3048)
			(stroke
				(width 0.1)
				(type default)
			)
			(layer "F.Fab")
		)
		(fp_line
			(start -0.12065 -0.2794)
			(end 0.12065 -0.2794)
			(stroke
				(width 0.1)
				(type default)
			)
			(layer "F.Fab")
		)
		(fp_line
			(start 0.120396 0.2794)
			(end -0.12065 0.2794)
			(stroke
				(width 0.1)
				(type default)
			)
			(layer "F.Fab")
		)
		(fp_line
			(start -0.12065 0.2794)
			(end -0.12065 0.3048)
			(stroke
				(width 0.1)
				(type default)
			)
			(layer "F.Fab")
		)
		(fp_line
			(start 0.67945 0.3048)
			(end 0.120396 0.3048)
			(stroke
				(width 0.1)
				(type default)
			)
			(layer "F.Fab")
		)
		(fp_line
			(start 0.120396 0.3048)
			(end 0.120396 0.2794)
			(stroke
				(width 0.1)
				(type default)
			)
			(layer "F.Fab")
		)
		(fp_line
			(start -0.12065 0.3048)
			(end -0.67945 0.3048)
			(stroke
				(width 0.1)
				(type default)
			)
			(layer "F.Fab")
		)
		(fp_line
			(start -0.67945 0.3048)
			(end -0.67945 -0.305054)
			(stroke
				(width 0.1)
				(type default)
			)
			(layer "F.Fab")
		)
		(pad "1" smd circle
			(at -0.40005 0 90)
			(size 0 0)
			(layers "F.Cu" "F.Mask" "F.Paste")
			(net "SW_P1V8_RETIMER_CPU0_BST_R")
		)
		(pad "2" smd circle
			(at 0.40005 0 90)
			(size 0 0)
			(layers "F.Cu" "F.Mask" "F.Paste")
			(net "SW_P1V8_RETIMER_CPU0_SW")
		)
	)
)
